(kicad_pcb
	(version 20260206)
	(generator "pcbnew")
	(generator_version "10.0")
	(general
		(thickness 1.21888)
		(legacy_teardrops no)
	)
	(paper "A4")
	(title_block
		(title "timecard-v9 — TimeCard-DC-V9_EXP.PcbDoc")
		(comment 1 "Time Appliance Project (Time Card) / footprints 290-302 of 402")
	)
	(layers
		(0 "F.Cu" signal "TOP")
		(4 "In1.Cu" signal "SGND")
		(6 "In2.Cu" signal "IN1")
		(8 "In3.Cu" signal "IN2")
		(10 "In4.Cu" signal "SGND1")
		(2 "B.Cu" signal "BOTTOM")
		(9 "F.Adhes" user "F.Adhesive")
		(11 "B.Adhes" user "B.Adhesive")
		(13 "F.Paste" user "Top Paste")
		(15 "B.Paste" user "Bottom Paste")
		(5 "F.SilkS" user "Top Overlay")
		(7 "B.SilkS" user "Bottom Overlay")
		(1 "F.Mask" user "Top Solder")
		(3 "B.Mask" user "Bottom Solder")
		(17 "Dwgs.User" user "User.Drawings")
		(19 "Cmts.User" user "User.Comments")
		(21 "Eco1.User" user "User.Eco1")
		(23 "Eco2.User" user "User.Eco2")
		(25 "Edge.Cuts" user)
		(27 "Margin" user)
		(31 "F.CrtYd" user "Top Courtyard")
		(29 "B.CrtYd" user "Bottom Courtyard")
		(35 "F.Fab" user "Top Component Center")
		(33 "B.Fab" user "Bottom Component Center")
	)
	(footprint "Vault:RESC1005X40X25LL05T05"
		(layer "B.Cu")
		(at 83.5116 66.12847)
		(property "Reference" "R66"
			(at -0.4186 -0.985339 0)
			(unlocked yes)
			(layer "B.SilkS")
			(effects
				(font
					(size 0.762 0.762)
					(thickness 0.2286)
				)
				(justify mirror)
			)
		)
		(property "Value" "0_1%_0402"
			(at -2.579871 -6.66537 270)
			(unlocked yes)
			(layer "B.SilkS")
			(hide yes)
			(effects
				(font
					(size 0.762 0.762)
					(thickness 0.2286)
				)
				(justify mirror)
			)
		)
		(sheetname "03-POWER")
		(sheetfile "03-POWER.kicad_sch")
		(duplicate_pad_numbers_are_jumpers no)
		(pad "1" smd rect
			(at -0.4 0 270)
			(size 0.45 0.45)
			(layers "B.Cu" "B.Mask" "B.Paste")
			(net "NetR66_1")
		)
		(pad "2" smd rect
			(at 0.4 0 270)
			(size 0.45 0.45)
			(layers "B.Cu" "B.Mask" "B.Paste")
			(net "GND")
		)
	)
	(footprint "Vault:FP-0402-L_1_0_1-W_0_5_0_1-IPC_C"
		(layer "B.Cu")
		(at 153.5216 129.7162 180)
		(property "Reference" "C95"
			(at 0.2286 1.455439 0)
			(unlocked yes)
			(layer "B.SilkS")
			(effects
				(font
					(size 0.762 0.762)
					(thickness 0.2286)
				)
				(justify mirror)
			)
		)
		(property "Value" "0.1uF_25V_0402"
			(at -2.465551 -9.839215 90)
			(unlocked yes)
			(layer "B.SilkS")
			(hide yes)
			(effects
				(font
					(size 0.762 0.762)
					(thickness 0.2286)
				)
				(justify mirror)
			)
		)
		(sheetname "09-USBUart_PPSMUX_UARTMUX")
		(sheetfile "09-USBUart_PPSMUX_UARTMUX.kicad_sch")
		(duplicate_pad_numbers_are_jumpers no)
		(fp_line
			(start 0.65607 0.7)
			(end -0.65607 0.7)
			(stroke
				(width 0.2)
				(type solid)
			)
			(layer "B.SilkS")
		)
		(fp_line
			(start 0.65607 -0.7)
			(end -0.65607 -0.7)
			(stroke
				(width 0.2)
				(type solid)
			)
			(layer "B.SilkS")
		)
		(fp_line
			(start 0.75607 0.4)
			(end -0.75607 0.4)
			(stroke
				(width 0.2)
				(type solid)
			)
			(layer "B.CrtYd")
		)
		(fp_line
			(start 0.75607 -0.4)
			(end 0.75607 0.4)
			(stroke
				(width 0.2)
				(type solid)
			)
			(layer "B.CrtYd")
		)
		(fp_line
			(start 0.75607 -0.4)
			(end -0.75607 -0.4)
			(stroke
				(width 0.2)
				(type solid)
			)
			(layer "B.CrtYd")
		)
		(fp_line
			(start -0.75607 -0.4)
			(end -0.75607 0.4)
			(stroke
				(width 0.2)
				(type solid)
			)
			(layer "B.CrtYd")
		)
		(fp_line
			(start 0.75607 0.4)
			(end -0.75607 0.4)
			(stroke
				(width 0.2)
				(type solid)
			)
			(layer "B.Fab")
		)
		(fp_line
			(start 0.75607 -0.4)
			(end 0.75607 0.4)
			(stroke
				(width 0.2)
				(type solid)
			)
			(layer "B.Fab")
		)
		(fp_line
			(start 0.75607 -0.4)
			(end -0.75607 -0.4)
			(stroke
				(width 0.2)
				(type solid)
			)
			(layer "B.Fab")
		)
		(fp_line
			(start 0.5 0)
			(end -0.5 0)
			(stroke
				(width 0.1)
				(type solid)
			)
			(layer "B.Fab")
		)
		(fp_line
			(start 0 -0.5)
			(end 0 0.5)
			(stroke
				(width 0.1)
				(type solid)
			)
			(layer "B.Fab")
		)
		(fp_line
			(start -0.75607 -0.4)
			(end -0.75607 0.4)
			(stroke
				(width 0.2)
				(type solid)
			)
			(layer "B.Fab")
		)
		(fp_text user "${REFERENCE}"
			(at -0.00001 -0.09602 360)
			(unlocked yes)
			(layer "B.Fab")
			(effects
				(font
					(face "Arial")
					(size 0.63 0.63)
					(thickness 0.1)
				)
				(justify left bottom mirror)
			)
		)
		(pad "1" smd rect
			(at -0.36554 0 180)
			(size 0.58106 0.51213)
			(layers "B.Cu" "B.Mask" "B.Paste")
			(net "GNSS2_P3V3")
			(solder_mask_margin 0)
			(solder_paste_margin 0)
		)
		(pad "2" smd rect
			(at 0.36554 0 180)
			(size 0.58106 0.51213)
			(layers "B.Cu" "B.Mask" "B.Paste")
			(net "GND")
			(solder_mask_margin 0)
			(solder_paste_margin 0)
		)
	)
	(footprint "Vault:RESC1005X40X25LL05T05"
		(layer "B.Cu")
		(at 225.37414 75.80021 90)
		(property "Reference" "R62"
			(at -0.0286 -1.573069 90)
			(unlocked yes)
			(layer "B.SilkS")
			(effects
				(font
					(size 0.762 0.762)
					(thickness 0.2286)
				)
				(justify mirror)
			)
		)
		(property "Value" "0_1%_0402"
			(at -2.579871 -6.66536 0)
			(unlocked yes)
			(layer "B.SilkS")
			(hide yes)
			(effects
				(font
					(size 0.762 0.762)
					(thickness 0.2286)
				)
				(justify mirror)
			)
		)
		(sheetname "03-POWER")
		(sheetfile "03-POWER.kicad_sch")
		(duplicate_pad_numbers_are_jumpers no)
		(pad "1" smd rect
			(at -0.4 0)
			(size 0.45 0.45)
			(layers "B.Cu" "B.Mask" "B.Paste")
			(net "NetR62_1")
		)
		(pad "2" smd rect
			(at 0.4 0)
			(size 0.45 0.45)
			(layers "B.Cu" "B.Mask" "B.Paste")
			(net "GND")
		)
	)
	(footprint "Vault:RESC1005X40X25NL10T10"
		(layer "B.Cu")
		(at 177.8867 81.69562 180)
		(property "Reference" "R70"
			(at 2.3937 -0.047511 0)
			(unlocked yes)
			(layer "B.SilkS")
			(effects
				(font
					(size 0.762 0.762)
					(thickness 0.2286)
				)
				(justify mirror)
			)
		)
		(property "Value" "4.7K_1%_0402"
			(at -2.783071 -8.468145 90)
			(unlocked yes)
			(layer "B.SilkS")
			(hide yes)
			(effects
				(font
					(size 0.762 0.762)
					(thickness 0.2286)
				)
				(justify mirror)
			)
		)
		(sheetname "03-POWER")
		(sheetfile "03-POWER.kicad_sch")
		(duplicate_pad_numbers_are_jumpers no)
		(pad "1" smd rect
			(at -0.425 0 90)
			(size 0.6 0.65)
			(layers "B.Cu" "B.Mask" "B.Paste")
			(net "NetR70_1")
		)
		(pad "2" smd rect
			(at 0.425 0 90)
			(size 0.6 0.65)
			(layers "B.Cu" "B.Mask" "B.Paste")
			(net "+12V")
		)
	)
	(footprint "Vault:RESC1005X35X25LL10T10"
		(layer "B.Cu")
		(at 174.3466 88.1162 180)
		(property "Reference" "R68"
			(at 1.0536 1.173079 0)
			(unlocked yes)
			(layer "B.SilkS")
			(effects
				(font
					(size 0.762 0.762)
					(thickness 0.2286)
				)
				(justify mirror)
			)
		)
		(property "Value" "2K_0.5%_0402"
			(at -2.452831 -6.538405 90)
			(unlocked yes)
			(layer "B.SilkS")
			(hide yes)
			(effects
				(font
					(size 0.762 0.762)
					(thickness 0.2286)
				)
				(justify mirror)
			)
		)
		(sheetname "03-POWER")
		(sheetfile "03-POWER.kicad_sch")
		(duplicate_pad_numbers_are_jumpers no)
		(pad "1" smd rect
			(at -0.375 0 90)
			(size 0.5 0.55)
			(layers "B.Cu" "B.Mask" "B.Paste")
			(net "NetR67_2")
		)
		(pad "2" smd rect
			(at 0.375 0 90)
			(size 0.5 0.55)
			(layers "B.Cu" "B.Mask" "B.Paste")
			(net "P3V3_SENSE")
		)
	)
	(footprint "Vault:CAPC1005X56X25NL10T15"
		(layer "B.Cu")
		(at 170.23267 91.0162)
		(property "Reference" "C66"
			(at 0.0786 -2.067801 180)
			(unlocked yes)
			(layer "B.SilkS")
			(effects
				(font
					(size 0.762 0.762)
					(thickness 0.2286)
				)
				(justify mirror)
			)
		)
		(property "Value" "0.1uF_25V_0402"
			(at 2.069035 -2.567191 180)
			(unlocked yes)
			(layer "B.SilkS")
			(hide yes)
			(effects
				(font
					(size 0.762 0.762)
					(thickness 0.2286)
				)
				(justify mirror)
			)
		)
		(sheetname "03-POWER")
		(sheetfile "03-POWER.kicad_sch")
		(duplicate_pad_numbers_are_jumpers no)
		(pad "1" smd rect
			(at -0.44 0 270)
			(size 0.64 0.68)
			(layers "B.Cu" "B.Mask" "B.Paste")
			(net "GND")
		)
		(pad "2" smd rect
			(at 0.44 0 270)
			(size 0.64 0.68)
			(layers "B.Cu" "B.Mask" "B.Paste")
			(net "+3.3V")
		)
	)
	(footprint "Vault:RESC1005X40X25NL05T05"
		(layer "B.Cu")
		(at 221.7216 102.3162 180)
		(property "Reference" "R178"
			(at -2.2968 -0.326921 0)
			(unlocked yes)
			(layer "B.SilkS")
			(effects
				(font
					(size 0.762 0.762)
					(thickness 0.2032)
				)
				(justify mirror)
			)
		)
		(property "Value" "200_1%_0402"
			(at -2.732271 -8.112675 90)
			(unlocked yes)
			(layer "B.SilkS")
			(hide yes)
			(effects
				(font
					(size 0.762 0.762)
					(thickness 0.2032)
				)
				(justify mirror)
			)
		)
		(sheetname "08-DIPSwitches_I2C")
		(sheetfile "08-DIPSwitches_I2C.kicad_sch")
		(duplicate_pad_numbers_are_jumpers no)
		(pad "1" smd rect
			(at -0.45 0 90)
			(size 0.55 0.55)
			(layers "B.Cu" "B.Mask" "B.Paste")
			(net "NetD12_1")
		)
		(pad "2" smd rect
			(at 0.45 0 90)
			(size 0.55 0.55)
			(layers "B.Cu" "B.Mask" "B.Paste")
			(net "DIP_SW_GPS2_SEL")
		)
	)
	(footprint "Vault:FP-MK212BG-MFG"
		(layer "B.Cu")
		(at 109.72193 73.1686 180)
		(property "Reference" "C58"
			(at -1.39967 1.159055 0)
			(unlocked yes)
			(layer "B.SilkS")
			(effects
				(font
					(size 0.762 0.762)
					(thickness 0.2286)
				)
				(justify left bottom mirror)
			)
		)
		(property "Value" "10uF"
			(at -1.5875 -5.233445 0)
			(unlocked yes)
			(layer "B.SilkS")
			(hide yes)
			(effects
				(font
					(size 0.762 0.762)
					(thickness 0.2286)
				)
				(justify left bottom mirror)
			)
		)
		(sheetname "05-GPS_IMU_SENSORS")
		(sheetfile "05-GPS_IMU_SENSORS.kicad_sch")
		(duplicate_pad_numbers_are_jumpers no)
		(fp_line
			(start 0.125 0.725)
			(end -0.125 0.725)
			(stroke
				(width 0.2)
				(type solid)
			)
			(layer "B.SilkS")
		)
		(fp_line
			(start 0.125 -0.725)
			(end -0.125 -0.725)
			(stroke
				(width 0.2)
				(type solid)
			)
			(layer "B.SilkS")
		)
		(fp_line
			(start 1.6 0.825)
			(end -1.6 0.825)
			(stroke
				(width 0.2)
				(type solid)
			)
			(layer "B.CrtYd")
		)
		(fp_line
			(start 1.6 -0.825)
			(end 1.6 0.825)
			(stroke
				(width 0.2)
				(type solid)
			)
			(layer "B.CrtYd")
		)
		(fp_line
			(start 1.6 -0.825)
			(end -1.6 -0.825)
			(stroke
				(width 0.2)
				(type solid)
			)
			(layer "B.CrtYd")
		)
		(fp_line
			(start -1.6 -0.825)
			(end -1.6 0.825)
			(stroke
				(width 0.2)
				(type solid)
			)
			(layer "B.CrtYd")
		)
		(fp_line
			(start 1.6 0.825)
			(end -1.6 0.825)
			(stroke
				(width 0.2)
				(type solid)
			)
			(layer "B.Fab")
		)
		(fp_line
			(start 1.6 -0.825)
			(end 1.6 0.825)
			(stroke
				(width 0.2)
				(type solid)
			)
			(layer "B.Fab")
		)
		(fp_line
			(start 1.6 -0.825)
			(end -1.6 -0.825)
			(stroke
				(width 0.2)
				(type solid)
			)
			(layer "B.Fab")
		)
		(fp_line
			(start 0.5 0)
			(end -0.5 0)
			(stroke
				(width 0.1)
				(type solid)
			)
			(layer "B.Fab")
		)
		(fp_line
			(start 0 -0.5)
			(end 0 0.5)
			(stroke
				(width 0.1)
				(type solid)
			)
			(layer "B.Fab")
		)
		(fp_line
			(start -1.6 -0.825)
			(end -1.6 0.825)
			(stroke
				(width 0.2)
				(type solid)
			)
			(layer "B.Fab")
		)
		(fp_text user "${REFERENCE}"
			(at -0.00001 -0.09601 360)
			(unlocked yes)
			(layer "B.Fab")
			(effects
				(font
					(face "Arial")
					(size 0.63 0.63)
					(thickness 0.1)
				)
				(justify left bottom mirror)
			)
		)
		(pad "1" smd rect
			(at -1 0 180)
			(size 1 1.25)
			(layers "B.Cu" "B.Mask" "B.Paste")
			(net "+3.3V")
			(solder_mask_margin 0)
			(solder_paste_margin 0)
		)
		(pad "2" smd rect
			(at 1 0 180)
			(size 1 1.25)
			(layers "B.Cu" "B.Mask" "B.Paste")
			(net "GND")
			(solder_mask_margin 0)
			(solder_paste_margin 0)
		)
	)
	(footprint "Vault:FP-RT0402-MFG"
		(layer "B.Cu")
		(at 176.3216 88.0162 180)
		(property "Reference" "R67"
			(at 0.3286 -1.626921 0)
			(unlocked yes)
			(layer "B.SilkS")
			(effects
				(font
					(size 0.762 0.762)
					(thickness 0.2286)
				)
				(justify mirror)
			)
		)
		(property "Value" "88.7K_0.5%_0402"
			(at -2.452831 -6.538405 90)
			(unlocked yes)
			(layer "B.SilkS")
			(hide yes)
			(effects
				(font
					(size 0.762 0.762)
					(thickness 0.2286)
				)
				(justify mirror)
			)
		)
		(sheetname "03-POWER")
		(sheetfile "03-POWER.kicad_sch")
		(duplicate_pad_numbers_are_jumpers no)
		(fp_line
			(start 0.5 0.7)
			(end -0.5 0.7)
			(stroke
				(width 0.2)
				(type solid)
			)
			(layer "B.SilkS")
		)
		(fp_line
			(start 0.5 -0.711)
			(end -0.5 -0.711)
			(stroke
				(width 0.2)
				(type solid)
			)
			(layer "B.SilkS")
		)
		(fp_line
			(start 0.85 0.4)
			(end -0.85 0.4)
			(stroke
				(width 0.2)
				(type solid)
			)
			(layer "B.CrtYd")
		)
		(fp_line
			(start 0.85 -0.4)
			(end 0.85 0.4)
			(stroke
				(width 0.2)
				(type solid)
			)
			(layer "B.CrtYd")
		)
		(fp_line
			(start 0.85 -0.4)
			(end -0.85 -0.4)
			(stroke
				(width 0.2)
				(type solid)
			)
			(layer "B.CrtYd")
		)
		(fp_line
			(start -0.85 -0.4)
			(end -0.85 0.4)
			(stroke
				(width 0.2)
				(type solid)
			)
			(layer "B.CrtYd")
		)
		(fp_line
			(start 0.85 0.4)
			(end -0.85 0.4)
			(stroke
				(width 0.2)
				(type solid)
			)
			(layer "B.Fab")
		)
		(fp_line
			(start 0.85 -0.4)
			(end 0.85 0.4)
			(stroke
				(width 0.2)
				(type solid)
			)
			(layer "B.Fab")
		)
		(fp_line
			(start 0.85 -0.4)
			(end -0.85 -0.4)
			(stroke
				(width 0.2)
				(type solid)
			)
			(layer "B.Fab")
		)
		(fp_line
			(start 0.5 0)
			(end -0.5 0)
			(stroke
				(width 0.1)
				(type solid)
			)
			(layer "B.Fab")
		)
		(fp_line
			(start 0 -0.5)
			(end 0 0.5)
			(stroke
				(width 0.1)
				(type solid)
			)
			(layer "B.Fab")
		)
		(fp_line
			(start -0.85 -0.4)
			(end -0.85 0.4)
			(stroke
				(width 0.2)
				(type solid)
			)
			(layer "B.Fab")
		)
		(fp_text user "${REFERENCE}"
			(at -0.00001 -0.09602 360)
			(unlocked yes)
			(layer "B.Fab")
			(effects
				(font
					(face "Arial")
					(size 0.63 0.63)
					(thickness 0.1)
				)
				(justify left bottom mirror)
			)
		)
		(pad "1" smd rect
			(at -0.5 0 180)
			(size 0.5 0.6)
			(layers "B.Cu" "B.Mask" "B.Paste")
			(net "P3V3_MUN_FB")
			(solder_mask_margin 0)
			(solder_paste_margin 0)
		)
		(pad "2" smd rect
			(at 0.5 0 180)
			(size 0.5 0.6)
			(layers "B.Cu" "B.Mask" "B.Paste")
			(net "NetR67_2")
			(solder_mask_margin 0)
			(solder_paste_margin 0)
		)
	)
	(footprint "Vault:RESC1005X40X25LL05T05"
		(layer "B.Cu")
		(at 83.6216 92.9162)
		(property "Reference" "R48"
			(at -0.1714 1.473069 180)
			(unlocked yes)
			(layer "B.SilkS")
			(effects
				(font
					(size 0.762 0.762)
					(thickness 0.2286)
				)
				(justify mirror)
			)
		)
		(property "Value" "DNI_0_1%_0402"
			(at -2.579871 -6.66536 270)
			(unlocked yes)
			(layer "B.SilkS")
			(hide yes)
			(effects
				(font
					(size 0.762 0.762)
					(thickness 0.2286)
				)
				(justify mirror)
			)
		)
		(sheetname "05-GPS_IMU_SENSORS")
		(sheetfile "05-GPS_IMU_SENSORS.kicad_sch")
		(duplicate_pad_numbers_are_jumpers no)
		(pad "1" smd rect
			(at -0.4 0 270)
			(size 0.45 0.45)
			(layers "B.Cu" "B.Mask" "B.Paste")
			(net "NetP1_5")
		)
		(pad "2" smd rect
			(at 0.4 0 270)
			(size 0.45 0.45)
			(layers "B.Cu" "B.Mask" "B.Paste")
			(net "MAC_FREQ_CTRL")
		)
	)
	(footprint "Vault:RESC1005X40X25LL05T05"
		(layer "B.Cu")
		(at 166.88457 94.6162 90)
		(property "Reference" "R80"
			(at -0.1286 -1.136039 90)
			(unlocked yes)
			(layer "B.SilkS")
			(effects
				(font
					(size 0.762 0.762)
					(thickness 0.2286)
				)
				(justify mirror)
			)
		)
		(property "Value" "0_1%_0402"
			(at -2.579871 -6.66536 0)
			(unlocked yes)
			(layer "B.SilkS")
			(hide yes)
			(effects
				(font
					(size 0.762 0.762)
					(thickness 0.2286)
				)
				(justify mirror)
			)
		)
		(sheetname "03-POWER")
		(sheetfile "03-POWER.kicad_sch")
		(duplicate_pad_numbers_are_jumpers no)
		(pad "1" smd rect
			(at -0.4 0)
			(size 0.45 0.45)
			(layers "B.Cu" "B.Mask" "B.Paste")
			(net "NetR80_1")
		)
		(pad "2" smd rect
			(at 0.4 0)
			(size 0.45 0.45)
			(layers "B.Cu" "B.Mask" "B.Paste")
			(net "+3.3V")
		)
	)
	(footprint "Resistors:RESC1608X50N"
		(layer "B.Cu")
		(at 145.9216 124.6162)
		(property "Reference" "R22"
			(at 1.06 -0.906655 0)
			(unlocked yes)
			(layer "B.SilkS")
			(effects
				(font
					(size 0.762 0.762)
					(thickness 0.2286)
				)
				(justify left bottom mirror)
			)
		)
		(property "Value" "ERJ-3EKF4701V"
			(at 0.4445 3.636645 0)
			(unlocked yes)
			(layer "B.SilkS")
			(hide yes)
			(effects
				(font
					(size 0.762 0.762)
					(thickness 0.2286)
				)
				(justify left bottom mirror)
			)
		)
		(sheetname "04-PCIe_JTAG")
		(sheetfile "04-PCIe_JTAG.kicad_sch")
		(duplicate_pad_numbers_are_jumpers no)
		(fp_line
			(start 0 0.5)
			(end 0 -0.5)
			(stroke
				(width 0.1524)
				(type solid)
			)
			(layer "B.SilkS")
		)
		(pad "1" smd rect
			(at -0.69 0 270)
			(size 1 0.72)
			(layers "B.Cu" "B.Mask" "B.Paste")
			(net "PCIE_PERST")
		)
		(pad "2" smd rect
			(at 0.69 0 270)
			(size 1 0.72)
			(layers "B.Cu" "B.Mask" "B.Paste")
			(net "+3.3V")
		)
	)
	(footprint "Vault:RESC1005X40X25LL05T05"
		(layer "B.Cu")
		(at 179.7216 81.9162 180)
		(property "Reference" "R69"
			(at -1.7968 -0.026921 0)
			(unlocked yes)
			(layer "B.SilkS")
			(effects
				(font
					(size 0.762 0.762)
					(thickness 0.2032)
				)
				(justify mirror)
			)
		)
		(property "Value" "0_1%_0402"
			(at -2.579871 -6.63996 90)
			(unlocked yes)
			(layer "B.SilkS")
			(hide yes)
			(effects
				(font
					(size 0.762 0.762)
					(thickness 0.2032)
				)
				(justify mirror)
			)
		)
		(sheetname "03-POWER")
		(sheetfile "03-POWER.kicad_sch")
		(duplicate_pad_numbers_are_jumpers no)
		(pad "1" smd rect
			(at -0.4 0 90)
			(size 0.45 0.45)
			(layers "B.Cu" "B.Mask" "B.Paste")
			(net "+12V")
		)
		(pad "2" smd rect
			(at 0.4 0 90)
			(size 0.45 0.45)
			(layers "B.Cu" "B.Mask" "B.Paste")
			(net "NetR69_2")
		)
	)
)
